(kicad_pcb
	(version 20260206)
	(generator "pcbnew")
	(generator_version "10.0")
	(general
		(thickness 1.6)
		(legacy_teardrops no)
	)
	(paper "A4")
	(title_block
		(title "04192023_DAF0TMB3IC0_F0TG_MB_C_brd_V02_OCP.brd")
		(comment 1 "Grand Teton / footprints 2994-3001 of 8354")
	)
	(layers
		(0 "F.Cu" signal "TOP")
		(4 "In1.Cu" signal "GND")
		(6 "In2.Cu" signal "IN1")
		(8 "In3.Cu" signal "GND1")
		(10 "In4.Cu" signal "IN2")
		(12 "In5.Cu" signal "GND2")
		(14 "In6.Cu" signal "IN3")
		(16 "In7.Cu" signal "GND3")
		(18 "In8.Cu" signal "VCC")
		(20 "In9.Cu" signal "VCC1")
		(22 "In10.Cu" signal "GND4")
		(24 "In11.Cu" signal "IN4")
		(26 "In12.Cu" signal "GND5")
		(28 "In13.Cu" signal "IN5")
		(30 "In14.Cu" signal "GND6")
		(32 "In15.Cu" signal "IN6")
		(34 "In16.Cu" signal "GND7")
		(2 "B.Cu" signal "BOTTOM")
		(9 "F.Adhes" user "F.Adhesive")
		(11 "B.Adhes" user "B.Adhesive")
		(13 "F.Paste" user "Package Geometry/Pastemask Top")
		(15 "B.Paste" user "Package Geometry/Pastemask Bottom")
		(5 "F.SilkS" user "Ref Des/Silkscreen Top")
		(7 "B.SilkS" user "Ref Des/Silkscreen Bottom")
		(1 "F.Mask" user "Board Geometry/Soldermask Top")
		(3 "B.Mask" user "Board Geometry/Soldermask Bottom")
		(17 "Dwgs.User" user "User.Drawings")
		(19 "Cmts.User" user "User.Comments")
		(21 "Eco1.User" user "User.Eco1")
		(23 "Eco2.User" user "User.Eco2")
		(25 "Edge.Cuts" user "Board Geometry/Outline")
		(27 "Margin" user)
		(31 "F.CrtYd" user "Package Geometry/Place Bound Top")
		(29 "B.CrtYd" user "Package Geometry/Place Bound Bottom")
		(35 "F.Fab" user "Ref Des/Assembly Top")
		(33 "B.Fab" user "Ref Des/Assembly Bottom")
	)
	(footprint ""
		(layer "F.Cu")
		(at 420.031418 -366.202214 90)
		(property "Reference" "PC202_2"
			(at 0 0 90)
			(layer "F.SilkS")
			(hide yes)
			(effects
				(font
					(size 1.27 1.27)
				)
			)
		)
		(property "Value" ""
			(at 0 0 90)
			(layer "F.Fab")
			(effects
				(font
					(size 1.27 1.27)
				)
			)
		)
		(duplicate_pad_numbers_are_jumpers no)
		(fp_line
			(start 0.7874 -0.4064)
			(end 0.7874 0.4064)
			(stroke
				(width 0.1524)
				(type default)
			)
			(layer "F.SilkS")
		)
		(fp_line
			(start -0.7874 -0.4064)
			(end 0.7874 -0.4064)
			(stroke
				(width 0.1524)
				(type default)
			)
			(layer "F.SilkS")
		)
		(fp_line
			(start 0.7874 0.4064)
			(end -0.7874 0.4064)
			(stroke
				(width 0.1524)
				(type default)
			)
			(layer "F.SilkS")
		)
		(fp_line
			(start -0.7874 0.4064)
			(end -0.7874 -0.4064)
			(stroke
				(width 0.1524)
				(type default)
			)
			(layer "F.SilkS")
		)
		(fp_line
			(start -0.12065 -0.305054)
			(end -0.12065 -0.2794)
			(stroke
				(width 0.1)
				(type default)
			)
			(layer "F.Fab")
		)
		(fp_line
			(start -0.67945 -0.305054)
			(end -0.12065 -0.305054)
			(stroke
				(width 0.1)
				(type default)
			)
			(layer "F.Fab")
		)
		(fp_line
			(start 0.67945 -0.3048)
			(end 0.67945 0.3048)
			(stroke
				(width 0.1)
				(type default)
			)
			(layer "F.Fab")
		)
		(fp_line
			(start 0.12065 -0.3048)
			(end 0.67945 -0.3048)
			(stroke
				(width 0.1)
				(type default)
			)
			(layer "F.Fab")
		)
		(fp_line
			(start 0.12065 -0.2794)
			(end 0.12065 -0.3048)
			(stroke
				(width 0.1)
				(type default)
			)
			(layer "F.Fab")
		)
		(fp_line
			(start -0.12065 -0.2794)
			(end 0.12065 -0.2794)
			(stroke
				(width 0.1)
				(type default)
			)
			(layer "F.Fab")
		)
		(fp_line
			(start 0.120396 0.2794)
			(end -0.12065 0.2794)
			(stroke
				(width 0.1)
				(type default)
			)
			(layer "F.Fab")
		)
		(fp_line
			(start -0.12065 0.2794)
			(end -0.12065 0.3048)
			(stroke
				(width 0.1)
				(type default)
			)
			(layer "F.Fab")
		)
		(fp_line
			(start 0.67945 0.3048)
			(end 0.120396 0.3048)
			(stroke
				(width 0.1)
				(type default)
			)
			(layer "F.Fab")
		)
		(fp_line
			(start 0.120396 0.3048)
			(end 0.120396 0.2794)
			(stroke
				(width 0.1)
				(type default)
			)
			(layer "F.Fab")
		)
		(fp_line
			(start -0.12065 0.3048)
			(end -0.67945 0.3048)
			(stroke
				(width 0.1)
				(type default)
			)
			(layer "F.Fab")
		)
		(fp_line
			(start -0.67945 0.3048)
			(end -0.67945 -0.305054)
			(stroke
				(width 0.1)
				(type default)
			)
			(layer "F.Fab")
		)
		(pad "1" smd circle
			(at -0.40005 0 90)
			(size 0 0)
			(layers "F.Cu" "F.Mask" "F.Paste")
			(net "PVDD11_S3_P0_VCCS")
		)
		(pad "2" smd circle
			(at 0.40005 0 90)
			(size 0 0)
			(layers "F.Cu" "F.Mask" "F.Paste")
			(net "GND")
		)
	)
	(footprint ""
		(layer "F.Cu")
		(at 89.898982 -55.713122 180)
		(property "Reference" "PC2151"
			(at 0 0 180)
			(layer "F.SilkS")
			(hide yes)
			(effects
				(font
					(size 1.27 1.27)
				)
			)
		)
		(property "Value" ""
			(at 0 0 180)
			(layer "F.Fab")
			(effects
				(font
					(size 1.27 1.27)
				)
			)
		)
		(duplicate_pad_numbers_are_jumpers no)
		(fp_line
			(start 0.7874 0.4064)
			(end -0.7874 0.4064)
			(stroke
				(width 0.1524)
				(type default)
			)
			(layer "F.SilkS")
		)
		(fp_line
			(start 0.7874 -0.4064)
			(end 0.7874 0.4064)
			(stroke
				(width 0.1524)
				(type default)
			)
			(layer "F.SilkS")
		)
		(fp_line
			(start -0.7874 0.4064)
			(end -0.7874 -0.4064)
			(stroke
				(width 0.1524)
				(type default)
			)
			(layer "F.SilkS")
		)
		(fp_line
			(start -0.7874 -0.4064)
			(end 0.7874 -0.4064)
			(stroke
				(width 0.1524)
				(type default)
			)
			(layer "F.SilkS")
		)
		(fp_line
			(start 0.67945 0.3048)
			(end 0.120396 0.3048)
			(stroke
				(width 0.1)
				(type default)
			)
			(layer "F.Fab")
		)
		(fp_line
			(start 0.67945 -0.3048)
			(end 0.67945 0.3048)
			(stroke
				(width 0.1)
				(type default)
			)
			(layer "F.Fab")
		)
		(fp_line
			(start 0.12065 -0.2794)
			(end 0.12065 -0.3048)
			(stroke
				(width 0.1)
				(type default)
			)
			(layer "F.Fab")
		)
		(fp_line
			(start 0.12065 -0.3048)
			(end 0.67945 -0.3048)
			(stroke
				(width 0.1)
				(type default)
			)
			(layer "F.Fab")
		)
		(fp_line
			(start 0.120396 0.3048)
			(end 0.120396 0.2794)
			(stroke
				(width 0.1)
				(type default)
			)
			(layer "F.Fab")
		)
		(fp_line
			(start 0.120396 0.2794)
			(end -0.12065 0.2794)
			(stroke
				(width 0.1)
				(type default)
			)
			(layer "F.Fab")
		)
		(fp_line
			(start -0.12065 0.3048)
			(end -0.67945 0.3048)
			(stroke
				(width 0.1)
				(type default)
			)
			(layer "F.Fab")
		)
		(fp_line
			(start -0.12065 0.2794)
			(end -0.12065 0.3048)
			(stroke
				(width 0.1)
				(type default)
			)
			(layer "F.Fab")
		)
		(fp_line
			(start -0.12065 -0.2794)
			(end 0.12065 -0.2794)
			(stroke
				(width 0.1)
				(type default)
			)
			(layer "F.Fab")
		)
		(fp_line
			(start -0.12065 -0.305054)
			(end -0.12065 -0.2794)
			(stroke
				(width 0.1)
				(type default)
			)
			(layer "F.Fab")
		)
		(fp_line
			(start -0.67945 0.3048)
			(end -0.67945 -0.305054)
			(stroke
				(width 0.1)
				(type default)
			)
			(layer "F.Fab")
		)
		(fp_line
			(start -0.67945 -0.305054)
			(end -0.12065 -0.305054)
			(stroke
				(width 0.1)
				(type default)
			)
			(layer "F.Fab")
		)
		(pad "1" smd circle
			(at -0.40005 0 180)
			(size 0 0)
			(layers "F.Cu" "F.Mask" "F.Paste")
			(net "P3V3_OCP_GATE_2")
		)
		(pad "2" smd circle
			(at 0.40005 0 180)
			(size 0 0)
			(layers "F.Cu" "F.Mask" "F.Paste")
			(net "GND")
		)
	)
	(footprint ""
		(layer "F.Cu")
		(at 306.831746 -416.899344 -90)
		(property "Reference" "C6504"
			(at 0 0 270)
			(layer "F.SilkS")
			(hide yes)
			(effects
				(font
					(size 1.27 1.27)
				)
			)
		)
		(property "Value" ""
			(at 0 0 270)
			(layer "F.Fab")
			(effects
				(font
					(size 1.27 1.27)
				)
			)
		)
		(duplicate_pad_numbers_are_jumpers no)
		(fp_line
			(start -0.299974 0.150114)
			(end -0.299974 -0.150114)
			(stroke
				(width 0.1)
				(type default)
			)
			(layer "F.Fab")
		)
		(fp_line
			(start 0.299974 0.150114)
			(end -0.299974 0.150114)
			(stroke
				(width 0.1)
				(type default)
			)
			(layer "F.Fab")
		)
		(fp_line
			(start -0.299974 -0.150114)
			(end 0.299974 -0.150114)
			(stroke
				(width 0.1)
				(type default)
			)
			(layer "F.Fab")
		)
		(fp_line
			(start 0.299974 -0.150114)
			(end 0.299974 0.150114)
			(stroke
				(width 0.1)
				(type default)
			)
			(layer "F.Fab")
		)
		(pad "1" smd rect
			(at -0.2667 0 270)
			(size 0.3048 0.381)
			(layers "F.Cu" "F.Mask" "F.Paste")
			(net "P5E_CPU0_P0_TX_BUF_C_DN<1>")
		)
		(pad "2" smd rect
			(at 0.2667 0 270)
			(size 0.3048 0.381)
			(layers "F.Cu" "F.Mask" "F.Paste")
			(net "P5E_CPU0_P0_TX_BUF_DN<1>")
		)
	)
	(footprint ""
		(layer "F.Cu")
		(at 159.18307 -74.75347 90)
		(property "Reference" "R116"
			(at 0 0 90)
			(layer "F.SilkS")
			(hide yes)
			(effects
				(font
					(size 1.27 1.27)
				)
			)
		)
		(property "Value" ""
			(at 0 0 90)
			(layer "F.Fab")
			(effects
				(font
					(size 1.27 1.27)
				)
			)
		)
		(duplicate_pad_numbers_are_jumpers no)
		(fp_line
			(start 0.7874 -0.4064)
			(end 0.7874 0.4064)
			(stroke
				(width 0.1524)
				(type default)
			)
			(layer "F.SilkS")
		)
		(fp_line
			(start -0.7874 -0.4064)
			(end 0.7874 -0.4064)
			(stroke
				(width 0.1524)
				(type default)
			)
			(layer "F.SilkS")
		)
		(fp_line
			(start 0.7874 0.4064)
			(end -0.7874 0.4064)
			(stroke
				(width 0.1524)
				(type default)
			)
			(layer "F.SilkS")
		)
		(fp_line
			(start -0.7874 0.4064)
			(end -0.7874 -0.4064)
			(stroke
				(width 0.1524)
				(type default)
			)
			(layer "F.SilkS")
		)
		(fp_line
			(start -0.12065 -0.305054)
			(end -0.12065 -0.2794)
			(stroke
				(width 0.1)
				(type default)
			)
			(layer "F.Fab")
		)
		(fp_line
			(start -0.67945 -0.305054)
			(end -0.12065 -0.305054)
			(stroke
				(width 0.1)
				(type default)
			)
			(layer "F.Fab")
		)
		(fp_line
			(start 0.67945 -0.3048)
			(end 0.67945 0.3048)
			(stroke
				(width 0.1)
				(type default)
			)
			(layer "F.Fab")
		)
		(fp_line
			(start 0.12065 -0.3048)
			(end 0.67945 -0.3048)
			(stroke
				(width 0.1)
				(type default)
			)
			(layer "F.Fab")
		)
		(fp_line
			(start 0.12065 -0.2794)
			(end 0.12065 -0.3048)
			(stroke
				(width 0.1)
				(type default)
			)
			(layer "F.Fab")
		)
		(fp_line
			(start -0.12065 -0.2794)
			(end 0.12065 -0.2794)
			(stroke
				(width 0.1)
				(type default)
			)
			(layer "F.Fab")
		)
		(fp_line
			(start 0.120396 0.2794)
			(end -0.12065 0.2794)
			(stroke
				(width 0.1)
				(type default)
			)
			(layer "F.Fab")
		)
		(fp_line
			(start -0.12065 0.2794)
			(end -0.12065 0.3048)
			(stroke
				(width 0.1)
				(type default)
			)
			(layer "F.Fab")
		)
		(fp_line
			(start 0.67945 0.3048)
			(end 0.120396 0.3048)
			(stroke
				(width 0.1)
				(type default)
			)
			(layer "F.Fab")
		)
		(fp_line
			(start 0.120396 0.3048)
			(end 0.120396 0.2794)
			(stroke
				(width 0.1)
				(type default)
			)
			(layer "F.Fab")
		)
		(fp_line
			(start -0.12065 0.3048)
			(end -0.67945 0.3048)
			(stroke
				(width 0.1)
				(type default)
			)
			(layer "F.Fab")
		)
		(fp_line
			(start -0.67945 0.3048)
			(end -0.67945 -0.305054)
			(stroke
				(width 0.1)
				(type default)
			)
			(layer "F.Fab")
		)
		(pad "1" smd circle
			(at -0.40005 0 90)
			(size 0 0)
			(layers "F.Cu" "F.Mask" "F.Paste")
			(net "IRQ_OCP_SFF_WAKE_BUF_N")
		)
		(pad "2" smd circle
			(at 0.40005 0 90)
			(size 0 0)
			(layers "F.Cu" "F.Mask" "F.Paste")
			(net "IRQ_LVC3_WAKE_N")
		)
	)
	(footprint ""
		(layer "F.Cu")
		(at 389.127492 -378.95403 -90)
		(property "Reference" "C876"
			(at 0 0 270)
			(layer "F.SilkS")
			(hide yes)
			(effects
				(font
					(size 1.27 1.27)
				)
			)
		)
		(property "Value" ""
			(at 0 0 270)
			(layer "F.Fab")
			(effects
				(font
					(size 1.27 1.27)
				)
			)
		)
		(duplicate_pad_numbers_are_jumpers no)
		(fp_line
			(start -0.299974 0.150114)
			(end -0.299974 -0.150114)
			(stroke
				(width 0.1)
				(type default)
			)
			(layer "F.Fab")
		)
		(fp_line
			(start 0.299974 0.150114)
			(end -0.299974 0.150114)
			(stroke
				(width 0.1)
				(type default)
			)
			(layer "F.Fab")
		)
		(fp_line
			(start -0.299974 -0.150114)
			(end 0.299974 -0.150114)
			(stroke
				(width 0.1)
				(type default)
			)
			(layer "F.Fab")
		)
		(fp_line
			(start 0.299974 -0.150114)
			(end 0.299974 0.150114)
			(stroke
				(width 0.1)
				(type default)
			)
			(layer "F.Fab")
		)
		(pad "1" smd rect
			(at -0.2667 0 270)
			(size 0.3048 0.381)
			(layers "F.Cu" "F.Mask" "F.Paste")
			(net "P5E_CPU0_P3_TX_C_DN<12>")
		)
		(pad "2" smd rect
			(at 0.2667 0 270)
			(size 0.3048 0.381)
			(layers "F.Cu" "F.Mask" "F.Paste")
			(net "P5E_CPU0_P3_TX_DN<12>")
		)
	)
	(footprint ""
		(layer "F.Cu")
		(at 189.79769 -36.0807)
		(property "Reference" "R1856"
			(at 0 0 0)
			(layer "F.SilkS")
			(hide yes)
			(effects
				(font
					(size 1.27 1.27)
				)
			)
		)
		(property "Value" ""
			(at 0 0 0)
			(layer "F.Fab")
			(effects
				(font
					(size 1.27 1.27)
				)
			)
		)
		(duplicate_pad_numbers_are_jumpers no)
		(fp_line
			(start -0.7874 -0.4064)
			(end 0.7874 -0.4064)
			(stroke
				(width 0.1524)
				(type default)
			)
			(layer "F.SilkS")
		)
		(fp_line
			(start -0.7874 0.4064)
			(end -0.7874 -0.4064)
			(stroke
				(width 0.1524)
				(type default)
			)
			(layer "F.SilkS")
		)
		(fp_line
			(start 0.7874 -0.4064)
			(end 0.7874 0.4064)
			(stroke
				(width 0.1524)
				(type default)
			)
			(layer "F.SilkS")
		)
		(fp_line
			(start 0.7874 0.4064)
			(end -0.7874 0.4064)
			(stroke
				(width 0.1524)
				(type default)
			)
			(layer "F.SilkS")
		)
		(fp_line
			(start -0.67945 -0.305054)
			(end -0.12065 -0.305054)
			(stroke
				(width 0.1)
				(type default)
			)
			(layer "F.Fab")
		)
		(fp_line
			(start -0.67945 0.3048)
			(end -0.67945 -0.305054)
			(stroke
				(width 0.1)
				(type default)
			)
			(layer "F.Fab")
		)
		(fp_line
			(start -0.12065 -0.305054)
			(end -0.12065 -0.2794)
			(stroke
				(width 0.1)
				(type default)
			)
			(layer "F.Fab")
		)
		(fp_line
			(start -0.12065 -0.2794)
			(end 0.12065 -0.2794)
			(stroke
				(width 0.1)
				(type default)
			)
			(layer "F.Fab")
		)
		(fp_line
			(start -0.12065 0.2794)
			(end -0.12065 0.3048)
			(stroke
				(width 0.1)
				(type default)
			)
			(layer "F.Fab")
		)
		(fp_line
			(start -0.12065 0.3048)
			(end -0.67945 0.3048)
			(stroke
				(width 0.1)
				(type default)
			)
			(layer "F.Fab")
		)
		(fp_line
			(start 0.120396 0.2794)
			(end -0.12065 0.2794)
			(stroke
				(width 0.1)
				(type default)
			)
			(layer "F.Fab")
		)
		(fp_line
			(start 0.120396 0.3048)
			(end 0.120396 0.2794)
			(stroke
				(width 0.1)
				(type default)
			)
			(layer "F.Fab")
		)
		(fp_line
			(start 0.12065 -0.3048)
			(end 0.67945 -0.3048)
			(stroke
				(width 0.1)
				(type default)
			)
			(layer "F.Fab")
		)
		(fp_line
			(start 0.12065 -0.2794)
			(end 0.12065 -0.3048)
			(stroke
				(width 0.1)
				(type default)
			)
			(layer "F.Fab")
		)
		(fp_line
			(start 0.67945 -0.3048)
			(end 0.67945 0.3048)
			(stroke
				(width 0.1)
				(type default)
			)
			(layer "F.Fab")
		)
		(fp_line
			(start 0.67945 0.3048)
			(end 0.120396 0.3048)
			(stroke
				(width 0.1)
				(type default)
			)
			(layer "F.Fab")
		)
		(pad "1" smd circle
			(at -0.40005 0)
			(size 0 0)
			(layers "F.Cu" "F.Mask" "F.Paste")
			(net "FM_SCM_PRSNT1_N")
		)
		(pad "2" smd circle
			(at 0.40005 0)
			(size 0 0)
			(layers "F.Cu" "F.Mask" "F.Paste")
			(net "FM_SCM_PRSNT1_R_N")
		)
	)
	(footprint ""
		(layer "F.Cu")
		(at 124.46 -28.854654 180)
		(property "Reference" "Y9"
			(at 1.37668 -2.9845 0)
			(unlocked yes)
			(layer "F.SilkS")
			(effects
				(font
					(size 0.7874 0.5842)
					(thickness 0.1524)
				)
				(justify left)
			)
		)
		(property "Value" ""
			(at 0 0 180)
			(layer "F.Fab")
			(effects
				(font
					(size 1.27 1.27)
				)
			)
		)
		(duplicate_pad_numbers_are_jumpers no)
		(fp_line
			(start 1.380236 1.579372)
			(end 1.380236 -1.579372)
			(stroke
				(width 0.1524)
				(type default)
			)
			(layer "F.SilkS")
		)
		(fp_line
			(start 1.380236 -1.579372)
			(end -1.380236 -1.579372)
			(stroke
				(width 0.1524)
				(type default)
			)
			(layer "F.SilkS")
		)
		(fp_line
			(start -1.380236 1.579372)
			(end 1.380236 1.579372)
			(stroke
				(width 0.1524)
				(type default)
			)
			(layer "F.SilkS")
		)
		(fp_line
			(start -1.380236 -1.579372)
			(end -1.380236 1.579372)
			(stroke
				(width 0.1524)
				(type default)
			)
			(layer "F.SilkS")
		)
		(fp_poly
			(pts
				(xy -0.774446 -1.816354) (xy -1.155446 -2.578354) (xy -0.393446 -2.578354)
			)
			(stroke
				(width 0)
				(type default)
			)
			(fill yes)
			(layer "F.SilkS")
		)
		(fp_line
			(start 1.050036 1.299972)
			(end 1.050036 -1.299972)
			(stroke
				(width 0.1)
				(type default)
			)
			(layer "F.Fab")
		)
		(fp_line
			(start 1.050036 -1.299972)
			(end -1.050036 -1.299972)
			(stroke
				(width 0.1)
				(type default)
			)
			(layer "F.Fab")
		)
		(fp_line
			(start -1.050036 1.299972)
			(end 1.050036 1.299972)
			(stroke
				(width 0.1)
				(type default)
			)
			(layer "F.Fab")
		)
		(fp_line
			(start -1.050036 -1.299972)
			(end -1.050036 1.299972)
			(stroke
				(width 0.1)
				(type default)
			)
			(layer "F.Fab")
		)
		(fp_poly
			(pts
				(xy -2.3114 -1.306068) (xy -2.3114 -0.544068) (xy -1.5494 -0.925068)
			)
			(stroke
				(width 0)
				(type default)
			)
			(fill yes)
			(layer "F.Fab")
		)
		(pad "1" smd rect
			(at -0.774954 -0.925068 180)
			(size 0.9144 1.016)
			(layers "F.Cu" "F.Mask" "F.Paste")
			(net "XTAL_USB_CPU0_HUB1_XIN")
		)
		(pad "2" smd rect
			(at -0.774954 0.925068 180)
			(size 0.9144 1.016)
			(layers "F.Cu" "F.Mask" "F.Paste")
			(net "GND")
		)
		(pad "3" smd rect
			(at 0.774954 0.925068 180)
			(size 0.9144 1.016)
			(layers "F.Cu" "F.Mask" "F.Paste")
			(net "XTAL_USB_CPU0_HUB1_XOUT")
		)
		(pad "4" smd rect
			(at 0.774954 -0.925068 180)
			(size 0.9144 1.016)
			(layers "F.Cu" "F.Mask" "F.Paste")
			(net "GND")
		)
	)
	(footprint ""
		(layer "F.Cu")
		(at 376.995182 -416.899344 -90)
		(property "Reference" "C6570"
			(at 0 0 270)
			(layer "F.SilkS")
			(hide yes)
			(effects
				(font
					(size 1.27 1.27)
				)
			)
		)
		(property "Value" ""
			(at 0 0 270)
			(layer "F.Fab")
			(effects
				(font
					(size 1.27 1.27)
				)
			)
		)
		(duplicate_pad_numbers_are_jumpers no)
		(fp_line
			(start -0.299974 0.150114)
			(end -0.299974 -0.150114)
			(stroke
				(width 0.1)
				(type default)
			)
			(layer "F.Fab")
		)
		(fp_line
			(start 0.299974 0.150114)
			(end -0.299974 0.150114)
			(stroke
				(width 0.1)
				(type default)
			)
			(layer "F.Fab")
		)
		(fp_line
			(start -0.299974 -0.150114)
			(end 0.299974 -0.150114)
			(stroke
				(width 0.1)
				(type default)
			)
			(layer "F.Fab")
		)
		(fp_line
			(start 0.299974 -0.150114)
			(end 0.299974 0.150114)
			(stroke
				(width 0.1)
				(type default)
			)
			(layer "F.Fab")
		)
		(pad "1" smd rect
			(at -0.2667 0 270)
			(size 0.3048 0.381)
			(layers "F.Cu" "F.Mask" "F.Paste")
			(net "P5E_CPU0_P2_TX_BUF_C_DN<2>")
		)
		(pad "2" smd rect
			(at 0.2667 0 270)
			(size 0.3048 0.381)
			(layers "F.Cu" "F.Mask" "F.Paste")
			(net "P5E_CPU0_P2_TX_BUF_DN<2>")
		)
	)
)
